# S9S_MB_2U (Grand Teton) — schematic netlist excerpt (pin names and nets, part order shuffled) for the footprints in the layout excerpt that follows; sources: Cadence DE-HDL packaged netlist, KiCad conversion of 03242023_DA0F0TMBIJ0_F0T_Motherboard_J_brd_V01_OCP.brd

PC1186  Q_CAPP  560UF 2.5V 20% OSCON  pkg THLF  page 272 : A = PVCCFA_EHV_FIVRA_CPU0 ; B = GND

X35  TP_TDR_4P_FTS  TP_TDR_4P_DIP EMPTY  pkg TH  page 310
  S1  = UNNAMED_310_TPTDR4PFTS_I15_S2
  P1  = T1_GND
  P2  = T1_GND
  S2  = UNNAMED_310_TPTDR4PFTS_I15_S1

(kicad_pcb
	(version 20260206)
	(generator "pcbnew")
	(generator_version "10.0")
	(general
		(thickness 1.6)
		(legacy_teardrops no)
	)
	(paper "A4")
	(title_block
		(title "03242023_DA0F0TMBIJ0_F0T_Motherboard_J_brd_V01_OCP.brd")
		(comment 1 "Grand Teton / footprints 825-826 of 6105")
	)
	(layers
		(0 "F.Cu" signal "TOP")
		(4 "In1.Cu" signal "GND")
		(6 "In2.Cu" signal "IN1")
		(8 "In3.Cu" signal "GND1")
		(10 "In4.Cu" signal "IN2")
		(12 "In5.Cu" signal "GND2")
		(14 "In6.Cu" signal "IN3")
		(16 "In7.Cu" signal "GND3")
		(18 "In8.Cu" signal "VCC")
		(20 "In9.Cu" signal "VCC1")
		(22 "In10.Cu" signal "GND4")
		(24 "In11.Cu" signal "IN4")
		(26 "In12.Cu" signal "GND5")
		(28 "In13.Cu" signal "IN5")
		(30 "In14.Cu" signal "GND6")
		(32 "In15.Cu" signal "IN6")
		(34 "In16.Cu" signal "GND7")
		(2 "B.Cu" signal "BOTTOM")
		(9 "F.Adhes" user "F.Adhesive")
		(11 "B.Adhes" user "B.Adhesive")
		(13 "F.Paste" user "Package Geometry/Pastemask Top")
		(15 "B.Paste" user "Package Geometry/Pastemask Bottom")
		(5 "F.SilkS" user "Ref Des/Silkscreen Top")
		(7 "B.SilkS" user "Ref Des/Silkscreen Bottom")
		(1 "F.Mask" user "Board Geometry/Soldermask Top")
		(3 "B.Mask" user "Board Geometry/Soldermask Bottom")
		(17 "Dwgs.User" user "User.Drawings")
		(19 "Cmts.User" user "User.Comments")
		(21 "Eco1.User" user "User.Eco1")
		(23 "Eco2.User" user "User.Eco2")
		(25 "Edge.Cuts" user "Board Geometry/Outline")
		(27 "Margin" user)
		(31 "F.CrtYd" user "Package Geometry/Place Bound Top")
		(29 "B.CrtYd" user "Package Geometry/Place Bound Bottom")
		(35 "F.Fab" user "Ref Des/Assembly Top")
		(33 "B.Fab" user "Ref Des/Assembly Bottom")
	)
	(footprint ""
		(layer "F.Cu")
		(at 477.30537 -211.009992 90)
		(property "Reference" "X35"
			(at -0.1778 -1.92913 90)
			(unlocked yes)
			(layer "F.SilkS")
			(effects
				(font
					(size 0.7874 0.5842)
					(thickness 0.1524)
				)
				(justify left)
			)
		)
		(property "Value" ""
			(at 0 0 90)
			(layer "F.Fab")
			(effects
				(font
					(size 1.27 1.27)
				)
			)
		)
		(property "Device Type" "TP_TDR_4P_FTS_TH-TP_TDR_4P_DIPA"
			(at 1.30175 1.27 180)
			(unlocked yes)
			(layer "F.Fab")
			(hide yes)
			(effects
				(font
					(size 0.635 0.4064)
					(thickness 0.1524)
				)
			)
		)
		(property "User Part Number" "N_A"
			(at 1.30175 1.27 180)
			(unlocked yes)
			(layer "Cmts.User")
			(hide yes)
			(effects
				(font
					(size 0.635 0.4064)
					(thickness 0.1524)
				)
			)
		)
		(duplicate_pad_numbers_are_jumpers no)
		(fp_line
			(start 2.54 -1.27)
			(end 0 -1.27)
			(stroke
				(width 0.1524)
				(type default)
			)
			(layer "F.SilkS")
		)
		(fp_line
			(start 0 -1.27)
			(end 0 -0.635)
			(stroke
				(width 0.1524)
				(type default)
			)
			(layer "F.SilkS")
		)
		(fp_line
			(start 2.54 -1.1303)
			(end 2.54 -1.27)
			(stroke
				(width 0.1524)
				(type default)
			)
			(layer "F.SilkS")
		)
		(fp_line
			(start 0 0.635)
			(end 0 1.905)
			(stroke
				(width 0.1524)
				(type default)
			)
			(layer "F.SilkS")
		)
		(fp_line
			(start 2.54 1.4097)
			(end 2.54 1.1303)
			(stroke
				(width 0.1524)
				(type default)
			)
			(layer "F.SilkS")
		)
		(fp_line
			(start 0 3.175)
			(end 0 3.81)
			(stroke
				(width 0.1524)
				(type default)
			)
			(layer "F.SilkS")
		)
		(fp_line
			(start 2.54 3.81)
			(end 2.54 3.6703)
			(stroke
				(width 0.1524)
				(type default)
			)
			(layer "F.SilkS")
		)
		(fp_line
			(start 0 3.81)
			(end 2.54 3.81)
			(stroke
				(width 0.1524)
				(type default)
			)
			(layer "F.SilkS")
		)
		(fp_poly
			(pts
				(xy -0.761746 0) (xy -2.285746 -0.762) (xy -2.285746 0.762)
			)
			(stroke
				(width 0)
				(type default)
			)
			(fill yes)
			(layer "F.SilkS")
		)
		(fp_line
			(start 2.54 -1.27)
			(end 0 -1.27)
			(stroke
				(width 0.1)
				(type default)
			)
			(layer "F.Fab")
		)
		(fp_line
			(start 0 -1.27)
			(end 0 3.81)
			(stroke
				(width 0.1)
				(type default)
			)
			(layer "F.Fab")
		)
		(fp_line
			(start 2.54 3.81)
			(end 2.54 -1.27)
			(stroke
				(width 0.1)
				(type default)
			)
			(layer "F.Fab")
		)
		(fp_line
			(start 0 3.81)
			(end 2.54 3.81)
			(stroke
				(width 0.1)
				(type default)
			)
			(layer "F.Fab")
		)
		(fp_poly
			(pts
				(xy -0.761746 0) (xy -2.285746 -0.762) (xy -2.285746 0.762)
			)
			(stroke
				(width 0)
				(type default)
			)
			(fill yes)
			(layer "F.Fab")
		)
		(pad "1" thru_hole circle
			(at 0 0 90)
			(size 1.0033 1.0033)
			(drill 0.249936)
			(layers "*.Cu" "*.Mask")
			(remove_unused_layers no)
			(net "TDR_DIFF_85_NECK_IN2_DP")
			(clearance 0.10795)
			(thermal_gap 0.10795)
			(padstack
				(mode front_inner_back)
				(layer "Inner"
					(shape circle)
					(size 0.8001 0.8001)
					(clearance 0.1524)
				)
				(layer "B.Cu"
					(shape circle)
					(size 1.0033 1.0033)
					(clearance 0.10795)
				)
			)
		)
		(pad "2" thru_hole circle
			(at 2.54 0 90)
			(size 1.9939 1.9939)
			(drill 0.249936)
			(layers "*.Cu" "*.Mask")
			(remove_unused_layers no)
			(net "T1_GND")
			(clearance 0.10795)
			(thermal_gap 0.10795)
			(padstack
				(mode front_inner_back)
				(layer "Inner"
					(shape circle)
					(size 0.8001 0.8001)
					(clearance 0.1524)
				)
				(layer "B.Cu"
					(shape circle)
					(size 1.9939 1.9939)
					(clearance 0.10795)
				)
			)
		)
		(pad "3" thru_hole circle
			(at 2.54 2.54 90)
			(size 1.9939 1.9939)
			(drill 0.249936)
			(layers "*.Cu" "*.Mask")
			(remove_unused_layers no)
			(net "T1_GND")
			(clearance 0.10795)
			(thermal_gap 0.10795)
			(padstack
				(mode front_inner_back)
				(layer "Inner"
					(shape circle)
					(size 0.8001 0.8001)
					(clearance 0.1524)
				)
				(layer "B.Cu"
					(shape circle)
					(size 1.9939 1.9939)
					(clearance 0.10795)
				)
			)
		)
		(pad "4" thru_hole circle
			(at 0 2.54 90)
			(size 1.0033 1.0033)
			(drill 0.249936)
			(layers "*.Cu" "*.Mask")
			(remove_unused_layers no)
			(net "TDR_DIFF_85_NECK_IN2_DN")
			(clearance 0.10795)
			(thermal_gap 0.10795)
			(padstack
				(mode front_inner_back)
				(layer "Inner"
					(shape circle)
					(size 0.8001 0.8001)
					(clearance 0.1524)
				)
				(layer "B.Cu"
					(shape circle)
					(size 1.0033 1.0033)
					(clearance 0.10795)
				)
			)
		)
	)
	(footprint ""
		(layer "F.Cu")
		(at 427.490128 -346.017342)
		(property "Reference" "PC1186"
			(at 0 0 0)
			(layer "F.SilkS")
			(hide yes)
			(effects
				(font
					(size 1.27 1.27)
				)
			)
		)
		(property "Value" ""
			(at 0 0 0)
			(layer "F.Fab")
			(effects
				(font
					(size 1.27 1.27)
				)
			)
		)
		(duplicate_pad_numbers_are_jumpers no)
		(fp_line
			(start 2.750058 0.999998)
			(end -2.750058 0.999998)
			(stroke
				(width 0.1524)
				(type default)
			)
			(layer "F.SilkS")
		)
		(fp_circle
			(center 0 0.999998)
			(end 2.750058 0.999998)
			(stroke
				(width 0.1524)
				(type default)
			)
			(fill no)
			(layer "F.SilkS")
		)
		(fp_poly
			(pts
				(arc
					(start 2.750058 0.999998)
					(mid 0 3.750056)
					(end -2.750058 0.999998)
				)
			)
			(stroke
				(width 0)
				(type default)
			)
			(fill yes)
			(layer "F.SilkS")
		)
		(fp_circle
			(center 0 0.999998)
			(end 2.750058 0.999998)
			(stroke
				(width 0.1)
				(type default)
			)
			(fill no)
			(layer "F.Fab")
		)
		(pad "1" thru_hole rect
			(at 0 0)
			(size 1.5748 1.5748)
			(drill 1.0668)
			(layers "*.Cu" "*.Mask")
			(remove_unused_layers no)
			(net "PVCCFA_EHV_FIVRA_CPU0")
			(clearance 0)
			(padstack
				(mode front_inner_back)
				(layer "Inner"
					(shape circle)
					(size 1.5748 1.5748)
					(clearance 0)
				)
				(layer "B.Cu"
					(shape rect)
					(size 1.5748 1.5748)
					(clearance 0)
				)
			)
		)
		(pad "2" thru_hole circle
			(at 0 1.999996)
			(size 1.5748 1.5748)
			(drill 1.0668)
			(layers "*.Cu" "*.Mask")
			(remove_unused_layers no)
			(net "GND")
			(clearance 0)
		)
	)
)
